# SCM (Grand Teton) — schematic netlist excerpt (pin names and nets, part order shuffled) for the footprints in the layout excerpt that follows; sources: Cadence DE-HDL packaged netlist, KiCad conversion of 12092022_DA0F0TMDCD0_F0T_Management_Board_D_brd_V3_OCP.brd

R784  Q_RES  0 5% EMPTY  pkg 0402LF  page 17 : A = P1V2_AUX ; B = ADCVREFEXT0
R374  Q_RES  120 1% CHIP  pkg 0402LF  page 20 : A = M_BMC_DDR4_MCKE ; B = P1V2_AUX

(kicad_pcb
	(version 20260206)
	(generator "pcbnew")
	(generator_version "10.0")
	(general
		(thickness 1.6)
		(legacy_teardrops no)
	)
	(paper "A4")
	(title_block
		(title "12092022_DA0F0TMDCD0_F0T_Management_Board_D_brd_V3_OCP.brd")
		(comment 1 "Grand Teton / footprints 1072-1073 of 1440")
	)
	(layers
		(0 "F.Cu" signal "TOP")
		(4 "In1.Cu" signal "GND")
		(6 "In2.Cu" signal "IN1")
		(8 "In3.Cu" signal "GND1")
		(10 "In4.Cu" signal "IN2")
		(12 "In5.Cu" signal "VCC")
		(14 "In6.Cu" signal "VCC1")
		(16 "In7.Cu" signal "IN3")
		(18 "In8.Cu" signal "GND2")
		(20 "In9.Cu" signal "IN4")
		(22 "In10.Cu" signal "GND3")
		(2 "B.Cu" signal "BOTTOM")
		(9 "F.Adhes" user "F.Adhesive")
		(11 "B.Adhes" user "B.Adhesive")
		(13 "F.Paste" user "Package Geometry/Pastemask Top")
		(15 "B.Paste" user "Package Geometry/Pastemask Bottom")
		(5 "F.SilkS" user "Ref Des/Silkscreen Top")
		(7 "B.SilkS" user "Ref Des/Silkscreen Bottom")
		(1 "F.Mask" user "Board Geometry/Soldermask Top")
		(3 "B.Mask" user "Board Geometry/Soldermask Bottom")
		(17 "Dwgs.User" user "User.Drawings")
		(19 "Cmts.User" user "User.Comments")
		(21 "Eco1.User" user "User.Eco1")
		(23 "Eco2.User" user "User.Eco2")
		(25 "Edge.Cuts" user "Board Geometry/Outline")
		(27 "Margin" user)
		(31 "F.CrtYd" user "Package Geometry/Place Bound Top")
		(29 "B.CrtYd" user "Package Geometry/Place Bound Bottom")
		(35 "F.Fab" user "Ref Des/Assembly Top")
		(33 "B.Fab" user "Ref Des/Assembly Bottom")
	)
	(footprint ""
		(layer "B.Cu")
		(at 71.858378 -47.106332 -90)
		(property "Reference" "R374"
			(at 0 0 90)
			(layer "B.SilkS")
			(hide yes)
			(effects
				(font
					(size 1.27 1.27)
				)
				(justify mirror)
			)
		)
		(property "Value" ""
			(at 0 0 90)
			(layer "B.Fab")
			(effects
				(font
					(size 1.27 1.27)
				)
				(justify mirror)
			)
		)
		(duplicate_pad_numbers_are_jumpers no)
		(fp_line
			(start -0.7874 0.4064)
			(end 0.7874 0.4064)
			(stroke
				(width 0.1524)
				(type default)
			)
			(layer "B.SilkS")
		)
		(fp_line
			(start 0.7874 0.4064)
			(end 0.7874 -0.4064)
			(stroke
				(width 0.1524)
				(type default)
			)
			(layer "B.SilkS")
		)
		(fp_line
			(start -0.7874 -0.4064)
			(end -0.7874 0.4064)
			(stroke
				(width 0.1524)
				(type default)
			)
			(layer "B.SilkS")
		)
		(fp_line
			(start 0.7874 -0.4064)
			(end -0.7874 -0.4064)
			(stroke
				(width 0.1524)
				(type default)
			)
			(layer "B.SilkS")
		)
		(fp_line
			(start -0.67945 0.3048)
			(end -0.120396 0.3048)
			(stroke
				(width 0.1)
				(type default)
			)
			(layer "B.Fab")
		)
		(fp_line
			(start -0.120396 0.3048)
			(end -0.120396 0.2794)
			(stroke
				(width 0.1)
				(type default)
			)
			(layer "B.Fab")
		)
		(fp_line
			(start 0.12065 0.3048)
			(end 0.67945 0.3048)
			(stroke
				(width 0.1)
				(type default)
			)
			(layer "B.Fab")
		)
		(fp_line
			(start 0.67945 0.3048)
			(end 0.67945 -0.305054)
			(stroke
				(width 0.1)
				(type default)
			)
			(layer "B.Fab")
		)
		(fp_line
			(start -0.120396 0.2794)
			(end 0.12065 0.2794)
			(stroke
				(width 0.1)
				(type default)
			)
			(layer "B.Fab")
		)
		(fp_line
			(start 0.12065 0.2794)
			(end 0.12065 0.3048)
			(stroke
				(width 0.1)
				(type default)
			)
			(layer "B.Fab")
		)
		(fp_line
			(start -0.12065 -0.2794)
			(end -0.12065 -0.3048)
			(stroke
				(width 0.1)
				(type default)
			)
			(layer "B.Fab")
		)
		(fp_line
			(start 0.12065 -0.2794)
			(end -0.12065 -0.2794)
			(stroke
				(width 0.1)
				(type default)
			)
			(layer "B.Fab")
		)
		(fp_line
			(start -0.67945 -0.3048)
			(end -0.67945 0.3048)
			(stroke
				(width 0.1)
				(type default)
			)
			(layer "B.Fab")
		)
		(fp_line
			(start -0.12065 -0.3048)
			(end -0.67945 -0.3048)
			(stroke
				(width 0.1)
				(type default)
			)
			(layer "B.Fab")
		)
		(fp_line
			(start 0.12065 -0.305054)
			(end 0.12065 -0.2794)
			(stroke
				(width 0.1)
				(type default)
			)
			(layer "B.Fab")
		)
		(fp_line
			(start 0.67945 -0.305054)
			(end 0.12065 -0.305054)
			(stroke
				(width 0.1)
				(type default)
			)
			(layer "B.Fab")
		)
		(pad "1" smd circle
			(at 0.40005 0 90)
			(size 0 0)
			(layers "B.Cu" "B.Mask" "B.Paste")
			(net "M_BMC_DDR4_MCKE")
		)
		(pad "2" smd circle
			(at -0.40005 0 90)
			(size 0 0)
			(layers "B.Cu" "B.Mask" "B.Paste")
			(net "P1V2_AUX")
		)
	)
	(footprint ""
		(layer "B.Cu")
		(at 56.462422 -72.46239 90)
		(property "Reference" "R784"
			(at 0 0 90)
			(layer "B.SilkS")
			(hide yes)
			(effects
				(font
					(size 1.27 1.27)
				)
				(justify mirror)
			)
		)
		(property "Value" ""
			(at 0 0 90)
			(layer "B.Fab")
			(effects
				(font
					(size 1.27 1.27)
				)
				(justify mirror)
			)
		)
		(duplicate_pad_numbers_are_jumpers no)
		(fp_line
			(start 0.7874 -0.4064)
			(end -0.7874 -0.4064)
			(stroke
				(width 0.1524)
				(type default)
			)
			(layer "B.SilkS")
		)
		(fp_line
			(start -0.7874 -0.4064)
			(end -0.7874 0.4064)
			(stroke
				(width 0.1524)
				(type default)
			)
			(layer "B.SilkS")
		)
		(fp_line
			(start 0.7874 0.4064)
			(end 0.7874 -0.4064)
			(stroke
				(width 0.1524)
				(type default)
			)
			(layer "B.SilkS")
		)
		(fp_line
			(start -0.7874 0.4064)
			(end 0.7874 0.4064)
			(stroke
				(width 0.1524)
				(type default)
			)
			(layer "B.SilkS")
		)
		(fp_line
			(start 0.67945 -0.305054)
			(end 0.12065 -0.305054)
			(stroke
				(width 0.1)
				(type default)
			)
			(layer "B.Fab")
		)
		(fp_line
			(start 0.12065 -0.305054)
			(end 0.12065 -0.2794)
			(stroke
				(width 0.1)
				(type default)
			)
			(layer "B.Fab")
		)
		(fp_line
			(start -0.12065 -0.3048)
			(end -0.67945 -0.3048)
			(stroke
				(width 0.1)
				(type default)
			)
			(layer "B.Fab")
		)
		(fp_line
			(start -0.67945 -0.3048)
			(end -0.67945 0.3048)
			(stroke
				(width 0.1)
				(type default)
			)
			(layer "B.Fab")
		)
		(fp_line
			(start 0.12065 -0.2794)
			(end -0.12065 -0.2794)
			(stroke
				(width 0.1)
				(type default)
			)
			(layer "B.Fab")
		)
		(fp_line
			(start -0.12065 -0.2794)
			(end -0.12065 -0.3048)
			(stroke
				(width 0.1)
				(type default)
			)
			(layer "B.Fab")
		)
		(fp_line
			(start 0.12065 0.2794)
			(end 0.12065 0.3048)
			(stroke
				(width 0.1)
				(type default)
			)
			(layer "B.Fab")
		)
		(fp_line
			(start -0.120396 0.2794)
			(end 0.12065 0.2794)
			(stroke
				(width 0.1)
				(type default)
			)
			(layer "B.Fab")
		)
		(fp_line
			(start 0.67945 0.3048)
			(end 0.67945 -0.305054)
			(stroke
				(width 0.1)
				(type default)
			)
			(layer "B.Fab")
		)
		(fp_line
			(start 0.12065 0.3048)
			(end 0.67945 0.3048)
			(stroke
				(width 0.1)
				(type default)
			)
			(layer "B.Fab")
		)
		(fp_line
			(start -0.120396 0.3048)
			(end -0.120396 0.2794)
			(stroke
				(width 0.1)
				(type default)
			)
			(layer "B.Fab")
		)
		(fp_line
			(start -0.67945 0.3048)
			(end -0.120396 0.3048)
			(stroke
				(width 0.1)
				(type default)
			)
			(layer "B.Fab")
		)
		(pad "1" smd circle
			(at 0.40005 0 270)
			(size 0 0)
			(layers "B.Cu" "B.Mask" "B.Paste")
			(net "P1V2_AUX")
		)
		(pad "2" smd circle
			(at -0.40005 0 270)
			(size 0 0)
			(layers "B.Cu" "B.Mask" "B.Paste")
			(net "ADCVREFEXT0")
		)
	)
)
